# T6G (Grand Teton) — schematic parts with pin connectivity, parts 8112–8155 of 8303; source: Cadence DE-HDL packaged netlist (pstxprt.dat, pstxnet.dat, pstchip.dat)

U56  ISL28022FRZT  ISL28022FRZ-T IC  pkg QFN16_TH_0-5_3X3XH  page 357
  1  A1  IN  = INA230_7_A1
  2  A0  IN  = INA230_7_A0
  3  \ext_clk||int\  BI  = P12V_OCP_V3_2_ADC_ALERT_R
  4  \sda||smbdat\  BI  = SMB_INA230_7_3V3AUX_SDA_R1
  5  \scl|||smbclk\  IN  = SMB_INA230_7_3V3AUX_SCL_R1
  6  NC0  TRI  = NC_INA230_7_NC0
  7  NC1  TRI  = NC_INA230_7_NC1
  8  NC2  TRI  = NC_INA230_7_NC2
  9  VCC  POWER  = P3V3_AUX
  10  GND  POWER  = GND
  11  VBUS  POWER  = P12V_OCP_V3_2
  12  VINM  IN  = VSENSE_P12V_INA230_7_INN
  13  VINP  IN  = VSENSE_P12V_INA230_7_INP
  14  NC3  TRI  = NC_INA230_7_NC3
  15  NC4  TRI  = NC_INA230_7_NC4
  16  NC5  TRI  = NC_INA230_7_NC5
  TH  TH_GND  POWER  = GND

U57  SCHOTTKY_DUAL_12A_3C  BAT54CW EMPTY  pkg SOT323  page 169
  1  B  IN  = P12V_AUX_DSC_VOL
  2  A  IN  = NC
  3  C  BI  = P12V_AUX_DSC_S1

U58  74LVC2G07DW7  74LVC2G07DW-7 IC  pkg SOT363_0-65_2X1-25XC  page 140
  1  \1a\  IN  = OCP_V3_2_PRSNT0_R_N
  2  GND  POWER  = GND
  3  \2a\  IN  = OCP_V3_2_PRSNT1_R_N
  4  \2y\  OUT  = HP_LVC3_OCP_V3_2_PRSNT2_N_R
  5  VCC  POWER  = P3V3_AUX
  6  \1y\  OUT  = HP_LVC3_OCP_V3_2_PRSNT2_N_R

U59  74LVC2G07DW7  74LVC2G07DW-7 IC  pkg SOT363_0-65_2X1-25XC  page 140
  1  \1a\  IN  = OCP_V3_2_PRSNT2_R_N
  2  GND  POWER  = GND
  3  \2a\  IN  = OCP_V3_2_PRSNT3_R_N
  4  \2y\  OUT  = HP_LVC3_OCP_V3_2_PRSNT2_N_R
  5  VCC  POWER  = P3V3_AUX
  6  \1y\  OUT  = HP_LVC3_OCP_V3_2_PRSNT2_N_R

U60  SCHOTTKY_DUAL_12A_3C  BAT54CW EMPTY  pkg SOT323  page 169
  1  B  IN  = P3V3_AUX_DSC_VOL
  2  A  IN  = NC
  3  C  BI  = P3V3_AUX_DSC_S1

U64  M24128BWMN6TP  M24128-BWMN6TP IC  pkg SOIC8XH  page 238
  1  E0  IN  = MB_FRU_ADDR0
  2  E1  IN  = MB_FRU_ADDR1
  3  E2  IN  = MB_FRU_ADDR2
  4  VSS  POWER  = GND
  5  SDA  BI  = SMB_FRU_3V3AUX_R1_SDA
  6  SCL  IN  = SMB_FRU_3V3AUX_R1_SCL
  7  \wc#\  IN  = PD_MB_FRU_WP
  8  VCC  POWER  = P3V3_AUX

U66  74LVC1G126SE7  74LVC1G126SE-7 IC  pkg SOT353_0-65_2X1-25  page 132
  1  OE  IN  = OCP_SFF_AUX_PWR_EN_R1
  2  A  IN  = FM_OCP_SFF_PWR_GOOD
  3  GND  POWER  = GND
  4  Y  OUT  = FB_BMC_ISOLATE_R1
  5  VCC  POWER  = P3V3_AUX

U67  74CBTLV3126PW  IC  pkg TSSOP14  page 132
  1  \1oe\  IN  = FB_BMC_ISOLATE
  2  \1a\  POWER  = NCSI_BMC_RXD1_R
  3  \1b\  BI  = NCSI_OCP_SFF_RXD1
  4  \2oe\  OUT  = FB_BMC_ISOLATE
  5  \2a\  BI  = NCSI_BMC_RXD0_R
  6  \2b\  BI  = NCSI_OCP_SFF_RXD0
  7  GND  POWER  = GND
  8  \3b\  BI  = NCSI_OCP_SFF_CRS_DV
  9  \3a\  BI  = NCSI_BMC_CRS_DV_R
  10  \3oe\  BI  = FB_BMC_ISOLATE
  11  \4b\  BI  = OCP_SFF_ISO1_RBT_ARB_IN
  12  \4a\  BI  = OCP_SFF_RBT_ARB_IN_R
  13  \4oe\  BI  = FB_BMC_ISOLATE
  14  VCC  BI  = P3V3_AUX

U75  74LVC1G17GW  IC  pkg TSSOP5  page 133
  1  NC  TRI  = NC
  2  A  IN  = RST_PERST_OCP_SFF_BUF_N
  3  GND  POWER  = GND
  4  Y  OCA  = RST_PERST_OCP_SFF_BUF2_N
  5  VCC  POWER  = P3V3_AUX

U82  SN74LVC1G07DBVR  IC  pkg SMLF  page 166
  1  NC  TRI  = NC
  2  A  IN  = BOOT_RDY_R1_N
  3  GND  POWER  = GND
  4  Y  OCA  = BOOT_RDY_BUF_R_LED
  5  VCC  POWER  = P1V8_AUX

U86  SN74LVC1G07DBVR  IC  pkg SMLF  page 166
  1  NC  TRI  = NC
  2  A  IN  = FM_SMERR_LED_N
  3  GND  POWER  = GND
  4  Y  OCA  = FM_SMERR_BUF_LED_N
  5  VCC  POWER  = P1V8_AUX

U90  PI6CV304LE  IC  pkg TSSOP8  page 133
  1  CLK_IN  IN  = CLK_50M_RMII_R
  2  OE  IN  = CLK_50M_EN
  3  Y0  OUT  = CLK_50M_BMC_MAC_R
  4  GND  POWER  = GND
  5  Y1  OUT  = CLK_50M_NCSI_OCP_1
  6  VDD  POWER  = P3V3_AUX
  7  Y2  OUT  = CLK_50M_NCSI_OCP_2
  8  Y3  OUT  = TP_CLK_50M_Y3

U92  SN74LVC1G07DBVR  IC  pkg SMLF  page 84
  1  NC  TRI  = NC
  2  A  IN  = SCM_IRQ_1V8_N
  3  GND  POWER  = GND
  4  Y  OCA  = SCM_IRQ_R_N
  5  VCC  POWER  = P1V8_AUX

U96  PCA9617ADP  IC  pkg TSSOP8_3XB  page 160
  1  VCCA  POWER  = PVDD18_S5_P0
  2  SCLA  BI  = SMB_CPU0_CPU1_SEC_SCL_R1
  3  SDAA  BI  = SMB_CPU0_CPU1_SEC_SDA_R1
  4  GND  POWER  = GND
  5  EN  IN  = PU_U96_EN
  6  SDAB  BI  = SMB_CPU0_CPU1_SEC_SDA
  7  SCLB  BI  = SMB_CPU0_CPU1_SEC_SCL
  8  VCCB  POWER  = P3V3_AUX

U98  PCA9306DP1  IC  pkg TSSOP8_3  page 148
  1  GND  POWER  = GND
  2  VREF1  POWER  = P1V8_AUX
  3  SCL1  BI  = SMB_M2_P1_1V8AUX_SCL_R
  4  SDA1  BI  = SMB_M2_P1_1V8AUX_SDA_R
  5  SDA2  BI  = SMB_SENSOR_M2_P1_3V3AUX_SDA
  6  SCL2  BI  = SMB_SENSOR_M2_P1_3V3AUX_SCL
  7  VREF2  POWER  = SMB_PCIE_M2_0_EN
  8  EN  IN  = SMB_PCIE_M2_0_EN

U99  SN74LVC1G07DBVR  EMPTY  pkg SMLF  page 171
  1  NC  TRI  = NC
  2  A  IN  = FW_RECOVERY_R
  3  GND  POWER  = GND
  4  Y  OCA  = SCM_JTAG_MUX_S1
  5  VCC  POWER  = P3V3_AUX

U100  RT9818C44GV  RT9818C-44GV IC  pkg SOT23_123_2-89X1-6  page 188
  1  \reset#\  OUT  = PWRGD_P5V_R
  2  GND  POWER  = GND
  3  VDD  POWER  = P5V

U101  SN74LVC1G07DBVR  IC  pkg SMLF  page 34
  1  NC  TRI  = NC
  2  A  IN  = FM_BIOS_POST_CMPLT_N
  3  GND  POWER  = GND
  4  Y  OCA  = FM_BIOS_POST_CMPLT_BUF_R1_N
  5  VCC  POWER  = PVDD18_S5_P0

U104  74LVC1G07GV  IC  pkg SC-74A_2-9X1-5  page 133
  1  NC1  TRI  = NC_U104_NC1
  2  A  IN  = FM_SYS_THROTTLE_N
  3  GND  POWER  = GND
  4  Y  OCA  = OCP_SFF_PWRBRK_BUFF_N
  5  VCC  POWER  = P3V3_AUX

U105  PI3CSW12ZUAEX  IC  pkg UQFN10_0-5_2X1-5  page 159
  1  \1d+\  BI  = I3C_0_SPD_DDRAF_CPU0_SCL
  2  \1d-\  BI  = I3C_0_SPD_DDRAF_CPU0_SDA
  3  \2d+\  BI  = I3C_SCM_0_R_SCL
  4  \2d-\  BI  = I3C_SCM_0_R_SDA
  5  GND  POWER  = GND
  6  \oe#\  IN  = FM_I3C_CPU0_MUX0_OE_N
  7  \d-\  BI  = I3C_SPD_DDRAF_CPU0_LVC1_SDA
  8  \d+\  BI  = I3C_SPD_DDRAF_CPU0_LVC1_SCL
  9  S  IN  = FM_I3C_CPU0_MUX0_SEL
  10  VDD  POWER  = P3V3_AUX

U106  PI3CSW12ZUAEX  IC  pkg UQFN10_0-5_2X1-5  page 159
  1  \1d+\  BI  = I3C_1_SPD_DDRGL_CPU0_SCL
  2  \1d-\  BI  = I3C_1_SPD_DDRGL_CPU0_SDA
  3  \2d+\  BI  = I3C_SCM_1_R_SCL
  4  \2d-\  BI  = I3C_SCM_1_R_SDA
  5  GND  POWER  = GND
  6  \oe#\  IN  = FM_I3C_CPU0_MUX1_OE_N
  7  \d-\  BI  = I3C_SPD_DDRGL_CPU0_LVC1_SDA
  8  \d+\  BI  = I3C_SPD_DDRGL_CPU0_LVC1_SCL
  9  S  IN  = FM_I3C_CPU0_MUX1_SEL
  10  VDD  POWER  = P3V3_AUX

U107  PI3CSW12ZUAEX  IC  pkg UQFN10_0-5_2X1-5  page 159
  1  \1d+\  BI  = I3C_0_SPD_DDRAF_CPU1_SCL
  2  \1d-\  BI  = I3C_0_SPD_DDRAF_CPU1_SDA
  3  \2d+\  BI  = I3C_SCM_2_R_SCL
  4  \2d-\  BI  = I3C_SCM_2_R_SDA
  5  GND  POWER  = GND
  6  \oe#\  IN  = FM_I3C_CPU1_MUX0_OE_N
  7  \d-\  BI  = I3C_SPD_DDRAF_CPU1_LVC1_SDA
  8  \d+\  BI  = I3C_SPD_DDRAF_CPU1_LVC1_SCL
  9  S  IN  = FM_I3C_CPU1_MUX0_SEL
  10  VDD  POWER  = P3V3_AUX

U108  PI3CSW12ZUAEX  IC  pkg UQFN10_0-5_2X1-5  page 159
  1  \1d+\  BI  = I3C_1_SPD_DDRGL_CPU1_SCL
  2  \1d-\  BI  = I3C_1_SPD_DDRGL_CPU1_SDA
  3  \2d+\  BI  = I3C_SCM_3_R_SCL
  4  \2d-\  BI  = I3C_SCM_3_R_SDA
  5  GND  POWER  = GND
  6  \oe#\  IN  = FM_I3C_CPU1_MUX1_OE_N
  7  \d-\  BI  = I3C_SPD_DDRGL_CPU1_LVC1_SDA
  8  \d+\  BI  = I3C_SPD_DDRGL_CPU1_LVC1_SCL
  9  S  IN  = FM_I3C_CPU1_MUX1_SEL
  10  VDD  POWER  = P3V3_AUX

U116  SN74AVC4T774PWR  IC  pkg TSSOP16XC  page 164
  1  DIR1  IN  = PVDD18_S5_P0
  2  DIR2  IN  = GND
  3  A1  BI  = UART_CPU0_SCM_UART1_TX
  4  A2  BI  = UART_CPU0_SCM_UART1_R_RX
  5  A3  BI  = UART_CPU0_UART0_TX
  6  A4  BI  = UART_CPU0_UART0_R_RX
  7  DIR3  IN  = PVDD18_S5_P0
  8  DIR4  IN  = GND
  9  OE  IN  = UART_LS_EN_N
  10  GND  POWER  = GND
  11  B4  BI  = UART_CPU0_LVC3_UART0_R_RX
  12  B3  BI  = UART_CPU0_LVC3_UART0_R_TX
  13  B2  BI  = UART_CPU0_SCM_LVC3_UART1_R_RX
  14  B1  BI  = UART_CPU0_SCM_LVC3_UART1_R_TX
  15  VCCB  POWER  = P3V3_AUX
  16  VCCA  POWER  = PVDD18_S5_P0

U124  SN74LVC1G07DBVR  IC  pkg SMLF  page 167
  1  NC  TRI  = NC
  2  A  IN  = FM_JTAG_BMC_R_OE
  3  GND  POWER  = GND
  4  Y  OCA  = JTAG_BMC_OE
  5  VCC  POWER  = U124_VCC

U134  74LVC2G07DW7  74LVC2G07DW-7 IC  pkg SOT363_0-65_2X1-25XC  page 145
  1  \1a\  IN  = RST_SMB_E1S_N
  2  GND  POWER  = GND
  3  \2a\  IN  = RST_SMB_E1S_N
  4  \2y\  OUT  = SMB_PCIE_E1S_ISO_EN_R2
  5  VCC  POWER  = P3V3_AUX
  6  \1y\  OUT  = RST_SMB_BUF_E1S_0_N

U142  LT6700CS61TRPBF  LT6700CS6-1#TRPBF EMPTY  pkg TSOT23-6_0-95_2-9X1-625  page 267
  1  OUTA  OUT  = A_HSC_LOW_GATE
  2  GND  POWER  = GND
  3  \ina+\  IN  = A_HSC_LOW
  4  \inb-\  IN  = A_HSC_HIGH
  5  VS  POWER  = U142_VS
  6  OUTB  OUT  = HSC_D_OC

U143  NCT7718W  IC  pkg MSOP8_0-65_3X3XE  page 267
  1  VDD  POWER  = P3V3_AUX
  2  \d+\  IN  = P12V_HSC_TEMP_D+
  3  \d-\  IN  = P12V_HSC_TEMP_D-
  4  \t_crit#\  OCA  = P12V_HSC_T_CRIT_N
  5  GND  POWER  = GND
  6  \alert#\  OCA  = P12V_HSC_TEMP_ALERT_N
  7  SDA  BI  = SMB_P12V_HSC_TEMP_SDA
  8  SCL  IN  = SMB_P12V_HSC_TEMP_SCL

U146  SN74AVC2T245RSWR  IC  pkg UQFN10_0-4_1-8X1-4  page 172
  1  DIR2  IN  = GND
  2  \oe_#\  IN  = JTAG_BMC_R_D_OE
  3  GND  POWER  = GND
  4  B2  OUT  = JTAG_TDO_R1
  5  B1  OUT  = JTAG_TDI_R
  6  VCCB  POWER  = PVDD18_S5_P0
  7  VCCA  POWER  = PVDD18_S5_P0
  8  A1  IN  = HDT_HDR_TDI
  9  A2  IN  = HDT_HDR_TDO_R
  10  DIR1  IN  = PVDD18_S5_P0

U147  SN74AVC2T245RSWR  IC  pkg UQFN10_0-4_1-8X1-4  page 172
  1  DIR2  IN  = GND
  2  \oe_#\  IN  = JTAG_BMC_OE_N
  3  GND  POWER  = GND
  4  B2  OUT  = JTAG_TDO_R1
  5  B1  OUT  = JTAG_TDI_R
  6  VCCB  POWER  = PVDD18_S5_P0
  7  VCCA  POWER  = P3V3_AUX
  8  A1  IN  = JTAG_SCM_MUX_TDO
  9  A2  IN  = JTAG_SCM_MUX_TDI
  10  DIR1  IN  = P3V3_AUX

U148  SN74AVC4T774PWR  IC  pkg TSSOP16XC  page 172
  1  DIR1  IN  = P3V3_AUX
  2  DIR2  IN  = P3V3_AUX
  3  A1  BI  = JTAG_SCM_MUX_TCK
  4  A2  BI  = JTAG_SCM_MUX_TMS
  5  A3  BI  = JTAG_SCM_TRST_N
  6  A4  BI  = JTAG_SCM_DBREQ_N
  7  DIR3  IN  = P3V3_AUX
  8  DIR4  IN  = P3V3_AUX
  9  OE  IN  = JTAG_BMC_OE_N
  10  GND  POWER  = GND
  11  B4  BI  = JTAG_DBREQ_R_N
  12  B3  BI  = JTAG_TRST_R_N
  13  B2  BI  = JTAG_TMS_R
  14  B1  BI  = JTAG_TCK_R
  15  VCCB  POWER  = PVDD18_S5_P0
  16  VCCA  POWER  = P3V3_AUX

U149  SN74AVC4T774PWR  IC  pkg TSSOP16XC  page 172
  1  DIR1  IN  = PVDD18_S5_P0
  2  DIR2  IN  = PVDD18_S5_P0
  3  A1  BI  = HDT_HDR_TCK
  4  A2  BI  = HDT_HDR_TMS
  5  A3  BI  = HDT_HDR_TRST_N
  6  A4  BI  = HDT_HDR_DBREQ_N
  7  DIR3  IN  = PVDD18_S5_P0
  8  DIR4  IN  = PVDD18_S5_P0
  9  OE  IN  = JTAG_BMC_R_D_OE
  10  GND  POWER  = GND
  11  B4  BI  = JTAG_DBREQ_R_N
  12  B3  BI  = JTAG_TRST_R_N
  13  B2  BI  = JTAG_TMS_R
  14  B1  BI  = JTAG_TCK_R
  15  VCCB  POWER  = PVDD18_S5_P0
  16  VCCA  POWER  = PVDD18_S5_P0

U150  SN74AVC4T774PWR  IC  pkg TSSOP16XC  page 173
  1  DIR1  IN  = PVDD18_S5_P0
  2  DIR2  IN  = PVDD18_S5_P0
  3  A1  BI  = JTAG_TCK
  4  A2  BI  = JTAG_TMS
  5  A3  BI  = JTAG_TRST_N
  6  A4  BI  = JTAG_DBREQ_N
  7  DIR3  IN  = PVDD18_S5_P0
  8  DIR4  IN  = PVDD18_S5_P0
  9  OE  IN  = CPU0_JTAG_BUF_OE
  10  GND  POWER  = GND
  11  B4  BI  = JTAG_P0_R_DBREQ_N
  12  B3  BI  = JTAG_P0_R_TRST_N
  13  B2  BI  = JTAG_P0_R_TMS
  14  B1  BI  = JTAG_P0_R_TCK
  15  VCCB  POWER  = PVDD18_S5_P0
  16  VCCA  POWER  = PVDD18_S5_P0

U151  SN74AVC4T774PWR  IC  pkg TSSOP16XC  page 173
  1  DIR1  IN  = PVDD18_S5_P0
  2  DIR2  IN  = PVDD18_S5_P0
  3  A1  BI  = JTAG_TCK
  4  A2  BI  = JTAG_TMS
  5  A3  BI  = JTAG_TRST_N
  6  A4  BI  = JTAG_DBREQ_N
  7  DIR3  IN  = PVDD18_S5_P0
  8  DIR4  IN  = PVDD18_S5_P0
  9  OE  IN  = CPU1_JTAG_BUF_OE
  10  GND  POWER  = GND
  11  B4  BI  = JTAG_P1_R_DBREQ_N
  12  B3  BI  = JTAG_P1_R_TRST_N
  13  B2  BI  = JTAG_P1_R_TMS
  14  B1  BI  = JTAG_P1_R_TCK
  15  VCCB  POWER  = PVDD18_S5_P1
  16  VCCA  POWER  = PVDD18_S5_P0

U152  SN74AVC2T245RSWR  IC  pkg UQFN10_0-4_1-8X1-4  page 173
  1  DIR2  IN  = GND
  2  \oe_#\  IN  = U152_OE_N
  3  GND  POWER  = GND
  4  B2  OUT  = JTAG_CPUX_TDO
  5  B1  OUT  = JTAG_CPUX_TDI_R1
  6  VCCB  POWER  = PVDD18_S5_P0
  7  VCCA  POWER  = PVDD18_S5_P0
  8  A1  IN  = JTAG_TDI
  9  A2  IN  = JTAG_TDO_R
  10  DIR1  IN  = PVDD18_S5_P0

U153  SN74AUC2G66DCTR  IC  pkg SSOP8  page 174
  1  \1a\  BI  = JTAG_CPUX_TDI
  2  \1b\  BI  = JTAG_CPU0_R_TDI
  3  \2c\  BI  = FM_PLD_CPU0_PRSNT_HDT_N
  4  GND  POWER  = GND
  5  \2a\  BI  = JTAG_CPUX_TDI
  6  \2b\  BI  = JTAG_CPU0_BYPASS
  7  \1c\  BI  = CPU0_HDT_BYPASS_SEL
  8  VCC  POWER  = PVDD18_S5_P0

U154  SN74AUC2G66DCTR  IC  pkg SSOP8  page 174
  1  \1a\  BI  = JTAG_CPU1_TDO
  2  \1b\  BI  = JTAG_CPUX_TDO_R
  3  \2c\  BI  = FM_PLD_CPU1_PRSNT_HDT_N
  4  GND  POWER  = GND
  5  \2a\  BI  = JTAG_CPU1_BYPASS
  6  \2b\  BI  = JTAG_CPUX_TDO_R
  7  \1c\  BI  = CPU1_HDT_BYPASS_SEL
  8  VCC  POWER  = PVDD18_S5_P0

U157  74LVC1G07GV  IC  pkg SC-74A_2-9X1-5  page 133
  1  NC1  TRI  = NC_U157_NC1
  2  A  IN  = OCP_SFF_WAKE_BUFF_R_N
  3  GND  POWER  = GND
  4  Y  OCA  = IRQ_LVC3_WAKE_BUF_N
  5  VCC  POWER  = P3V3_AUX

U158  MOSFET_NCH_GDS_ESD_PROTECTED  2N7002K IC  pkg SOT23_GDSXC  page 242
  D  D  BI  = FM_P12V_HSC_EN_N
  G  G  IN  = FM_P12V_HSC_EN_R
  S  S  BI  = GND

U160  74LV4052PW  IC  pkg TSSOP16_0-65_5X4-4XH  page 171
  1  \2y0\  BI  = TP_JTAG_SCM_SLOT3_R_TMS
  2  \2y2\  BI  = JTAG_SCM_PLD_R_TMS
  3  \2z\  BI  = JTAG_SCM_TMS
  4  \2y3\  BI  = JTAG_SCM_PLD_R_TMS
  5  \2y1\  BI  = JTAG_SCM_MUX_R_TMS
  6  E_N  BI  = U160_EN_N
  7  VEE  POWER  = GND
  8  GND  POWER  = GND
  9  S1  BI  = SCM_JTAG_MUX_S1
  10  S0  BI  = SCM_JTAG_MUX_S0_R1
  11  \1y3\  BI  = JTAG_SCM_PLD_R_TCK
  12  \1y0\  BI  = TP_JTAG_SCM_SLOT3_R_TCK
  13  \1z\  BI  = JTAG_SCM_TCK
  14  \1y1\  BI  = JTAG_SCM_MUX_R_TCK
  15  \1y2\  BI  = JTAG_SCM_PLD_R_TCK
  16  VCC  POWER  = P3V3_AUX

U166  SCHOTTKY_DUAL_12A_3C  BAT54CW IC  pkg SOT323  page 187
  1  B  IN  = P3V3_STBY_R
  2  A  IN  = P3V_BAT_R
  3  C  BI  = P3V3_RTC_AUX

U167  NCP698SQ15T1G  EMPTY  pkg SC82-AB-4_1-3_2X1-25  page 187
  1  GND  POWER  = GND
  2  VIN  IN  = P1V5_BAT_IN
  3  VOUT  OUT  = P1V5_BAT_OUT
  4  EN  IN  = BAT_LDO_EN

U175  LTC4307CMS8  IC  pkg MSOP8  page 248
  1  ENABLE  IN  = SMB_BMC_SWB_EN_R
  2  SCL_OUT  BI  = SMB_BMC_SWB_BUF_R_SCL
  3  SCL_IN  BI  = SMB_BMC_SWB_R_SCL
  4  GND  POWER  = GND
  5  READY  OUT  = NC
  6  SDA_IN  BI  = SMB_BMC_SWB_R_SDA
  7  SDA_OUT  BI  = SMB_BMC_SWB_BUF_R_SDA
  8  VCC  POWER  = P3V3_AUX

U176  LTC4307CMS8  EMPTY  pkg MSOP8  page 248
  1  ENABLE  IN  = SMB_BMC_SWB_EN_R2
  2  SCL_OUT  BI  = I3C_BMC_SWB_BUF_R_SCL
  3  SCL_IN  BI  = I3C_BMC_SWB_R_SCL
  4  GND  POWER  = GND
  5  READY  OUT  = NC
  6  SDA_IN  BI  = I3C_BMC_SWB_R_SDA
  7  SDA_OUT  BI  = I3C_BMC_SWB_BUF_R_SDA
  8  VCC  POWER  = P3V3_AUX
